(kicad_pcb
	(version 20260206)
	(generator "pcbnew")
	(generator_version "10.0")
	(general
		(thickness 1.6)
		(legacy_teardrops no)
	)
	(paper "A4")
	(title_block
		(title "pdpb — Lightning_PDPB_BRD.brd")
		(comment 1 "Lightning (Wiwynn / Facebook NVMe JBOF) / footprints 245-251 of 1140")
	)
	(layers
		(0 "F.Cu" signal "TOP")
		(4 "In1.Cu" signal "L2GND")
		(6 "In2.Cu" signal "L3")
		(8 "In3.Cu" signal "L4VCC")
		(10 "In4.Cu" signal "L5VCC")
		(12 "In5.Cu" signal "L6")
		(14 "In6.Cu" signal "L7GND")
		(2 "B.Cu" signal "BOTTOM")
		(9 "F.Adhes" user "F.Adhesive")
		(11 "B.Adhes" user "B.Adhesive")
		(13 "F.Paste" user "Package Geometry/Pastemask Top")
		(15 "B.Paste" user "Package Geometry/Pastemask Bottom")
		(5 "F.SilkS" user "Ref Des/Silkscreen Top")
		(7 "B.SilkS" user "Ref Des/Silkscreen Bottom")
		(1 "F.Mask" user "Board Geometry/Soldermask Top")
		(3 "B.Mask" user "Board Geometry/Soldermask Bottom")
		(17 "Dwgs.User" user "User.Drawings")
		(19 "Cmts.User" user "User.Comments")
		(21 "Eco1.User" user "User.Eco1")
		(23 "Eco2.User" user "User.Eco2")
		(25 "Edge.Cuts" user "Board Geometry/Outline")
		(27 "Margin" user)
		(31 "F.CrtYd" user "Package Geometry/Place Bound Top")
		(29 "B.CrtYd" user "Package Geometry/Place Bound Bottom")
		(35 "F.Fab" user "Ref Des/Assembly Top")
		(33 "B.Fab" user "Ref Des/Assembly Bottom")
	)
	(footprint ""
		(layer "F.Cu")
		(at 225.1075 -244.405658 90)
		(property "Reference" "R9796"
			(at 0 0 90)
			(layer "F.SilkS")
			(hide yes)
			(effects
				(font
					(size 1.27 1.27)
				)
			)
		)
		(property "Value" "0R2J-2-GP"
			(at 0.064008 -3.993896 90)
			(unlocked yes)
			(layer "F.Fab")
			(hide yes)
			(effects
				(font
					(size 1.016 1.016)
					(thickness 0.1524)
				)
			)
		)
		(property "Device Type" "R402H16"
			(at 0.064008 -5.517896 90)
			(unlocked yes)
			(layer "F.Fab")
			(hide yes)
			(effects
				(font
					(size 1.016 1.016)
					(thickness 0.1524)
				)
			)
		)
		(duplicate_pad_numbers_are_jumpers no)
		(fp_line
			(start 0.508 -0.9398)
			(end -0.508 -0.9398)
			(stroke
				(width 0.1524)
				(type default)
			)
			(layer "F.SilkS")
		)
		(fp_line
			(start -0.508 -0.9398)
			(end -0.508 0.9398)
			(stroke
				(width 0.1524)
				(type default)
			)
			(layer "F.SilkS")
		)
		(fp_rect
			(start -0.508 0.9398)
			(end 0.508 -0.9398)
			(stroke
				(width 0)
				(type default)
			)
			(fill no)
			(layer "F.CrtYd")
		)
		(fp_rect
			(start -0.508 0.9398)
			(end 0.508 -0.9398)
			(stroke
				(width 0)
				(type default)
			)
			(fill no)
			(layer "F.Fab")
		)
		(pad "1" smd custom
			(at 0 -0.4445 90)
			(size 0.1397 0.1397)
			(layers "F.Cu" "F.Mask" "F.Paste")
			(net "ATTN_LED_DR2_R")
			(options
				(clearance outline)
				(anchor circle)
			)
			(primitives
				(gr_poly
					(pts
						(arc
							(start -0.1778 -0.2794)
							(mid -0.249642 -0.249642)
							(end -0.2794 -0.1778)
						)
						(arc
							(start -0.2794 0.1778)
							(mid -0.249642 0.249642)
							(end -0.1778 0.2794)
						)
						(arc
							(start 0.1778 0.2794)
							(mid 0.249642 0.249642)
							(end 0.2794 0.1778)
						)
						(arc
							(start 0.2794 -0.1778)
							(mid 0.249642 -0.249642)
							(end 0.1778 -0.2794)
						)
					)
					(width 0)
					(fill yes)
				)
			)
		)
		(pad "2" smd custom
			(at 0 0.4445 90)
			(size 0.1397 0.1397)
			(layers "F.Cu" "F.Mask" "F.Paste")
			(net "ATTN_LED_DR2_N")
			(options
				(clearance outline)
				(anchor circle)
			)
			(primitives
				(gr_poly
					(pts
						(arc
							(start -0.1778 -0.2794)
							(mid -0.249642 -0.249642)
							(end -0.2794 -0.1778)
						)
						(arc
							(start -0.2794 0.1778)
							(mid -0.249642 0.249642)
							(end -0.1778 0.2794)
						)
						(arc
							(start 0.1778 0.2794)
							(mid 0.249642 0.249642)
							(end 0.2794 0.1778)
						)
						(arc
							(start 0.2794 -0.1778)
							(mid 0.249642 -0.249642)
							(end 0.1778 -0.2794)
						)
					)
					(width 0)
					(fill yes)
				)
			)
		)
	)
	(footprint ""
		(layer "F.Cu")
		(at 98.806 -320.167 90)
		(property "Reference" "R9472"
			(at 0 0 90)
			(layer "F.SilkS")
			(hide yes)
			(effects
				(font
					(size 1.27 1.27)
				)
			)
		)
		(property "Value" "4K7R2J-2-GP"
			(at 0.064008 -3.993896 90)
			(unlocked yes)
			(layer "F.Fab")
			(hide yes)
			(effects
				(font
					(size 1.016 1.016)
					(thickness 0.1524)
				)
			)
		)
		(property "Device Type" "R402H16"
			(at 0.064008 -5.517896 90)
			(unlocked yes)
			(layer "F.Fab")
			(hide yes)
			(effects
				(font
					(size 1.016 1.016)
					(thickness 0.1524)
				)
			)
		)
		(duplicate_pad_numbers_are_jumpers no)
		(fp_line
			(start 0.508 -0.9398)
			(end -0.508 -0.9398)
			(stroke
				(width 0.1524)
				(type default)
			)
			(layer "F.SilkS")
		)
		(fp_line
			(start -0.508 -0.9398)
			(end -0.508 0.9398)
			(stroke
				(width 0.1524)
				(type default)
			)
			(layer "F.SilkS")
		)
		(fp_rect
			(start -0.508 0.9398)
			(end 0.508 -0.9398)
			(stroke
				(width 0)
				(type default)
			)
			(fill no)
			(layer "F.CrtYd")
		)
		(fp_rect
			(start -0.508 0.9398)
			(end 0.508 -0.9398)
			(stroke
				(width 0)
				(type default)
			)
			(fill no)
			(layer "F.Fab")
		)
		(pad "1" smd custom
			(at 0 -0.4445 90)
			(size 0.1397 0.1397)
			(layers "F.Cu" "F.Mask" "F.Paste")
			(net "P3V3")
			(options
				(clearance outline)
				(anchor circle)
			)
			(primitives
				(gr_poly
					(pts
						(arc
							(start -0.1778 -0.2794)
							(mid -0.249642 -0.249642)
							(end -0.2794 -0.1778)
						)
						(arc
							(start -0.2794 0.1778)
							(mid -0.249642 0.249642)
							(end -0.1778 0.2794)
						)
						(arc
							(start 0.1778 0.2794)
							(mid 0.249642 0.249642)
							(end 0.2794 0.1778)
						)
						(arc
							(start 0.2794 -0.1778)
							(mid 0.249642 -0.249642)
							(end 0.1778 -0.2794)
						)
					)
					(width 0)
					(fill yes)
				)
			)
		)
		(pad "2" smd custom
			(at 0 0.4445 90)
			(size 0.1397 0.1397)
			(layers "F.Cu" "F.Mask" "F.Paste")
			(net "SSD_PRSNT_NET6")
			(options
				(clearance outline)
				(anchor circle)
			)
			(primitives
				(gr_poly
					(pts
						(arc
							(start -0.1778 -0.2794)
							(mid -0.249642 -0.249642)
							(end -0.2794 -0.1778)
						)
						(arc
							(start -0.2794 0.1778)
							(mid -0.249642 0.249642)
							(end -0.1778 0.2794)
						)
						(arc
							(start 0.1778 0.2794)
							(mid 0.249642 0.249642)
							(end 0.2794 0.1778)
						)
						(arc
							(start 0.2794 -0.1778)
							(mid 0.249642 -0.249642)
							(end 0.1778 -0.2794)
						)
					)
					(width 0)
					(fill yes)
				)
			)
		)
	)
	(footprint ""
		(layer "F.Cu")
		(at 87.757 -320.167 90)
		(property "Reference" "R9515"
			(at 0 0 90)
			(layer "F.SilkS")
			(hide yes)
			(effects
				(font
					(size 1.27 1.27)
				)
			)
		)
		(property "Value" "4K7R2J-2-GP"
			(at 0.064008 -3.993896 90)
			(unlocked yes)
			(layer "F.Fab")
			(hide yes)
			(effects
				(font
					(size 1.016 1.016)
					(thickness 0.1524)
				)
			)
		)
		(property "Device Type" "R402H16"
			(at 0.064008 -5.517896 90)
			(unlocked yes)
			(layer "F.Fab")
			(hide yes)
			(effects
				(font
					(size 1.016 1.016)
					(thickness 0.1524)
				)
			)
		)
		(duplicate_pad_numbers_are_jumpers no)
		(fp_line
			(start 0.508 -0.9398)
			(end -0.508 -0.9398)
			(stroke
				(width 0.1524)
				(type default)
			)
			(layer "F.SilkS")
		)
		(fp_line
			(start -0.508 -0.9398)
			(end -0.508 0.9398)
			(stroke
				(width 0.1524)
				(type default)
			)
			(layer "F.SilkS")
		)
		(fp_rect
			(start -0.508 0.9398)
			(end 0.508 -0.9398)
			(stroke
				(width 0)
				(type default)
			)
			(fill no)
			(layer "F.CrtYd")
		)
		(fp_rect
			(start -0.508 0.9398)
			(end 0.508 -0.9398)
			(stroke
				(width 0)
				(type default)
			)
			(fill no)
			(layer "F.Fab")
		)
		(pad "1" smd custom
			(at 0 -0.4445 90)
			(size 0.1397 0.1397)
			(layers "F.Cu" "F.Mask" "F.Paste")
			(net "P3V3")
			(options
				(clearance outline)
				(anchor circle)
			)
			(primitives
				(gr_poly
					(pts
						(arc
							(start -0.1778 -0.2794)
							(mid -0.249642 -0.249642)
							(end -0.2794 -0.1778)
						)
						(arc
							(start -0.2794 0.1778)
							(mid -0.249642 0.249642)
							(end -0.1778 0.2794)
						)
						(arc
							(start 0.1778 0.2794)
							(mid 0.249642 0.249642)
							(end 0.2794 0.1778)
						)
						(arc
							(start 0.2794 -0.1778)
							(mid 0.249642 -0.249642)
							(end 0.1778 -0.2794)
						)
					)
					(width 0)
					(fill yes)
				)
			)
		)
		(pad "2" smd custom
			(at 0 0.4445 90)
			(size 0.1397 0.1397)
			(layers "F.Cu" "F.Mask" "F.Paste")
			(net "SSD11_CLK0_OE_N")
			(options
				(clearance outline)
				(anchor circle)
			)
			(primitives
				(gr_poly
					(pts
						(arc
							(start -0.1778 -0.2794)
							(mid -0.249642 -0.249642)
							(end -0.2794 -0.1778)
						)
						(arc
							(start -0.2794 0.1778)
							(mid -0.249642 0.249642)
							(end -0.1778 0.2794)
						)
						(arc
							(start 0.1778 0.2794)
							(mid 0.249642 0.249642)
							(end 0.2794 0.1778)
						)
						(arc
							(start 0.2794 -0.1778)
							(mid 0.249642 -0.249642)
							(end 0.1778 -0.2794)
						)
					)
					(width 0)
					(fill yes)
				)
			)
		)
	)
	(footprint ""
		(layer "F.Cu")
		(at 21.231606 -59.10961 180)
		(property "Reference" "R9926"
			(at 0 0 180)
			(layer "F.SilkS")
			(hide yes)
			(effects
				(font
					(size 1.27 1.27)
				)
			)
		)
		(property "Value" "47KR2J-2-GP"
			(at 0.064008 -3.993896 180)
			(unlocked yes)
			(layer "F.Fab")
			(hide yes)
			(effects
				(font
					(size 1.016 1.016)
					(thickness 0.1524)
				)
			)
		)
		(property "Device Type" "R402H16"
			(at 0.064008 -5.517896 180)
			(unlocked yes)
			(layer "F.Fab")
			(hide yes)
			(effects
				(font
					(size 1.016 1.016)
					(thickness 0.1524)
				)
			)
		)
		(duplicate_pad_numbers_are_jumpers no)
		(fp_line
			(start 0.508 -0.9398)
			(end -0.508 -0.9398)
			(stroke
				(width 0.1524)
				(type default)
			)
			(layer "F.SilkS")
		)
		(fp_line
			(start -0.508 -0.9398)
			(end -0.508 0.9398)
			(stroke
				(width 0.1524)
				(type default)
			)
			(layer "F.SilkS")
		)
		(fp_rect
			(start -0.508 0.9398)
			(end 0.508 -0.9398)
			(stroke
				(width 0)
				(type default)
			)
			(fill no)
			(layer "F.CrtYd")
		)
		(fp_rect
			(start -0.508 0.9398)
			(end 0.508 -0.9398)
			(stroke
				(width 0)
				(type default)
			)
			(fill no)
			(layer "F.Fab")
		)
		(pad "1" smd custom
			(at 0 -0.4445 180)
			(size 0.1397 0.1397)
			(layers "F.Cu" "F.Mask" "F.Paste")
			(net "P3V3")
			(options
				(clearance outline)
				(anchor circle)
			)
			(primitives
				(gr_poly
					(pts
						(arc
							(start -0.1778 -0.2794)
							(mid -0.249642 -0.249642)
							(end -0.2794 -0.1778)
						)
						(arc
							(start -0.2794 0.1778)
							(mid -0.249642 0.249642)
							(end -0.1778 0.2794)
						)
						(arc
							(start 0.1778 0.2794)
							(mid 0.249642 0.249642)
							(end 0.2794 0.1778)
						)
						(arc
							(start 0.2794 -0.1778)
							(mid 0.249642 -0.249642)
							(end 0.1778 -0.2794)
						)
					)
					(width 0)
					(fill yes)
				)
			)
		)
		(pad "2" smd custom
			(at 0 0.4445 180)
			(size 0.1397 0.1397)
			(layers "F.Cu" "F.Mask" "F.Paste")
			(net "ATTN_LED_DR14_N")
			(options
				(clearance outline)
				(anchor circle)
			)
			(primitives
				(gr_poly
					(pts
						(arc
							(start -0.1778 -0.2794)
							(mid -0.249642 -0.249642)
							(end -0.2794 -0.1778)
						)
						(arc
							(start -0.2794 0.1778)
							(mid -0.249642 0.249642)
							(end -0.1778 0.2794)
						)
						(arc
							(start 0.1778 0.2794)
							(mid 0.249642 0.249642)
							(end 0.2794 0.1778)
						)
						(arc
							(start 0.2794 -0.1778)
							(mid 0.249642 -0.249642)
							(end 0.1778 -0.2794)
						)
					)
					(width 0)
					(fill yes)
				)
			)
		)
	)
	(footprint ""
		(layer "F.Cu")
		(at 89.789 -225.806 90)
		(property "Reference" "R9479"
			(at 0 0 90)
			(layer "F.SilkS")
			(hide yes)
			(effects
				(font
					(size 1.27 1.27)
				)
			)
		)
		(property "Value" "4K7R2J-2-GP"
			(at 0.064008 -3.993896 90)
			(unlocked yes)
			(layer "F.Fab")
			(hide yes)
			(effects
				(font
					(size 1.016 1.016)
					(thickness 0.1524)
				)
			)
		)
		(property "Device Type" "R402H16"
			(at 0.064008 -5.517896 90)
			(unlocked yes)
			(layer "F.Fab")
			(hide yes)
			(effects
				(font
					(size 1.016 1.016)
					(thickness 0.1524)
				)
			)
		)
		(duplicate_pad_numbers_are_jumpers no)
		(fp_line
			(start 0.508 -0.9398)
			(end -0.508 -0.9398)
			(stroke
				(width 0.1524)
				(type default)
			)
			(layer "F.SilkS")
		)
		(fp_line
			(start -0.508 -0.9398)
			(end -0.508 0.9398)
			(stroke
				(width 0.1524)
				(type default)
			)
			(layer "F.SilkS")
		)
		(fp_rect
			(start -0.508 0.9398)
			(end 0.508 -0.9398)
			(stroke
				(width 0)
				(type default)
			)
			(fill no)
			(layer "F.CrtYd")
		)
		(fp_rect
			(start -0.508 0.9398)
			(end 0.508 -0.9398)
			(stroke
				(width 0)
				(type default)
			)
			(fill no)
			(layer "F.Fab")
		)
		(pad "1" smd custom
			(at 0 -0.4445 90)
			(size 0.1397 0.1397)
			(layers "F.Cu" "F.Mask" "F.Paste")
			(net "P3V3")
			(options
				(clearance outline)
				(anchor circle)
			)
			(primitives
				(gr_poly
					(pts
						(arc
							(start -0.1778 -0.2794)
							(mid -0.249642 -0.249642)
							(end -0.2794 -0.1778)
						)
						(arc
							(start -0.2794 0.1778)
							(mid -0.249642 0.249642)
							(end -0.1778 0.2794)
						)
						(arc
							(start 0.1778 0.2794)
							(mid 0.249642 0.249642)
							(end 0.2794 0.1778)
						)
						(arc
							(start 0.2794 -0.1778)
							(mid 0.249642 -0.249642)
							(end 0.1778 -0.2794)
						)
					)
					(width 0)
					(fill yes)
				)
			)
		)
		(pad "2" smd custom
			(at 0 0.4445 90)
			(size 0.1397 0.1397)
			(layers "F.Cu" "F.Mask" "F.Paste")
			(net "SSD_PRSNT_NET12")
			(options
				(clearance outline)
				(anchor circle)
			)
			(primitives
				(gr_poly
					(pts
						(arc
							(start -0.1778 -0.2794)
							(mid -0.249642 -0.249642)
							(end -0.2794 -0.1778)
						)
						(arc
							(start -0.2794 0.1778)
							(mid -0.249642 0.249642)
							(end -0.1778 0.2794)
						)
						(arc
							(start 0.1778 0.2794)
							(mid 0.249642 0.249642)
							(end 0.2794 0.1778)
						)
						(arc
							(start 0.2794 -0.1778)
							(mid 0.249642 -0.249642)
							(end 0.1778 -0.2794)
						)
					)
					(width 0)
					(fill yes)
				)
			)
		)
	)
	(footprint ""
		(layer "F.Cu")
		(at 14.826488 -425.843192 180)
		(property "Reference" "C9538"
			(at 0 0 180)
			(layer "F.SilkS")
			(hide yes)
			(effects
				(font
					(size 1.27 1.27)
				)
			)
		)
		(property "Value" "SCD01U50V2KX-1GP"
			(at 1.1811 -2.7051 180)
			(unlocked yes)
			(layer "F.Fab")
			(hide yes)
			(effects
				(font
					(size 1.016 1.016)
					(thickness 0.1524)
				)
			)
		)
		(property "Device Type" "C402H22"
			(at 1.1811 -4.2291 180)
			(unlocked yes)
			(layer "F.Fab")
			(hide yes)
			(effects
				(font
					(size 1.016 1.016)
					(thickness 0.1524)
				)
			)
		)
		(duplicate_pad_numbers_are_jumpers no)
		(fp_rect
			(start -0.4318 0.9525)
			(end 0.4318 -0.9525)
			(stroke
				(width 0)
				(type default)
			)
			(fill no)
			(layer "F.CrtYd")
		)
		(fp_rect
			(start -0.4318 0.9525)
			(end 0.4318 -0.9525)
			(stroke
				(width 0)
				(type default)
			)
			(fill no)
			(layer "F.Fab")
		)
		(pad "1" smd custom
			(at 0 -0.4445 180)
			(size 0.1524 0.1524)
			(layers "F.Cu" "F.Mask" "F.Paste")
			(net "PE_100M_CLK3_P")
			(options
				(clearance outline)
				(anchor circle)
			)
			(primitives
				(gr_poly
					(pts
						(arc
							(start 0.3048 -0.2032)
							(mid 0.275042 -0.275042)
							(end 0.2032 -0.3048)
						)
						(arc
							(start -0.2032 -0.3048)
							(mid -0.275042 -0.275042)
							(end -0.3048 -0.2032)
						)
						(arc
							(start -0.3048 0.2032)
							(mid -0.275042 0.275042)
							(end -0.2032 0.3048)
						)
						(arc
							(start 0.2032 0.3048)
							(mid 0.275042 0.275042)
							(end 0.3048 0.2032)
						)
					)
					(width 0)
					(fill yes)
				)
			)
		)
		(pad "2" smd custom
			(at 0 0.4445 180)
			(size 0.1524 0.1524)
			(layers "F.Cu" "F.Mask" "F.Paste")
			(net "PE_100M_CLK3_C_P")
			(options
				(clearance outline)
				(anchor circle)
			)
			(primitives
				(gr_poly
					(pts
						(arc
							(start 0.3048 -0.2032)
							(mid 0.275042 -0.275042)
							(end 0.2032 -0.3048)
						)
						(arc
							(start -0.2032 -0.3048)
							(mid -0.275042 -0.275042)
							(end -0.3048 -0.2032)
						)
						(arc
							(start -0.3048 0.2032)
							(mid -0.275042 0.275042)
							(end -0.2032 0.3048)
						)
						(arc
							(start 0.2032 0.3048)
							(mid 0.275042 0.275042)
							(end 0.3048 0.2032)
						)
					)
					(width 0)
					(fill yes)
				)
			)
		)
	)
	(footprint ""
		(layer "F.Cu")
		(at 84.455 -204.978 90)
		(property "Reference" "PR9039"
			(at 0 0 90)
			(layer "F.SilkS")
			(hide yes)
			(effects
				(font
					(size 1.27 1.27)
				)
			)
		)
		(property "Value" "4K7R2F-GP"
			(at 0.064008 -3.993896 90)
			(unlocked yes)
			(layer "F.Fab")
			(hide yes)
			(effects
				(font
					(size 1.016 1.016)
					(thickness 0.1524)
				)
			)
		)
		(property "Device Type" "R402H16"
			(at 0.064008 -5.517896 90)
			(unlocked yes)
			(layer "F.Fab")
			(hide yes)
			(effects
				(font
					(size 1.016 1.016)
					(thickness 0.1524)
				)
			)
		)
		(duplicate_pad_numbers_are_jumpers no)
		(fp_line
			(start 0.508 -0.9398)
			(end -0.508 -0.9398)
			(stroke
				(width 0.1524)
				(type default)
			)
			(layer "F.SilkS")
		)
		(fp_line
			(start -0.508 -0.9398)
			(end -0.508 0.9398)
			(stroke
				(width 0.1524)
				(type default)
			)
			(layer "F.SilkS")
		)
		(fp_rect
			(start -0.508 0.9398)
			(end 0.508 -0.9398)
			(stroke
				(width 0)
				(type default)
			)
			(fill no)
			(layer "F.CrtYd")
		)
		(fp_rect
			(start -0.508 0.9398)
			(end 0.508 -0.9398)
			(stroke
				(width 0)
				(type default)
			)
			(fill no)
			(layer "F.Fab")
		)
		(pad "1" smd custom
			(at 0 -0.4445 90)
			(size 0.1397 0.1397)
			(layers "F.Cu" "F.Mask" "F.Paste")
			(net "VDD_DIFF_3")
			(options
				(clearance outline)
				(anchor circle)
			)
			(primitives
				(gr_poly
					(pts
						(arc
							(start -0.1778 -0.2794)
							(mid -0.249642 -0.249642)
							(end -0.2794 -0.1778)
						)
						(arc
							(start -0.2794 0.1778)
							(mid -0.249642 0.249642)
							(end -0.1778 0.2794)
						)
						(arc
							(start 0.1778 0.2794)
							(mid 0.249642 0.249642)
							(end 0.2794 0.1778)
						)
						(arc
							(start 0.2794 -0.1778)
							(mid 0.249642 -0.249642)
							(end 0.1778 -0.2794)
						)
					)
					(width 0)
					(fill yes)
				)
			)
		)
		(pad "2" smd custom
			(at 0 0.4445 90)
			(size 0.1397 0.1397)
			(layers "F.Cu" "F.Mask" "F.Paste")
			(net "CLK_BUF_EU3_SMB_A1_TRI")
			(options
				(clearance outline)
				(anchor circle)
			)
			(primitives
				(gr_poly
					(pts
						(arc
							(start -0.1778 -0.2794)
							(mid -0.249642 -0.249642)
							(end -0.2794 -0.1778)
						)
						(arc
							(start -0.2794 0.1778)
							(mid -0.249642 0.249642)
							(end -0.1778 0.2794)
						)
						(arc
							(start 0.1778 0.2794)
							(mid 0.249642 0.249642)
							(end 0.2794 0.1778)
						)
						(arc
							(start 0.2794 -0.1778)
							(mid 0.249642 -0.249642)
							(end 0.1778 -0.2794)
						)
					)
					(width 0)
					(fill yes)
				)
			)
		)
	)
)
